# BASEBOARD_FAB2 (Tioga Pass) — schematic netlist excerpt (pin names and nets, part order shuffled) for the footprints in the layout excerpt that follows; sources: Cadence DE-HDL packaged netlist, KiCad conversion of Wiwynn_Tioga_Pass_MB.brd

Y8F1  CRYSTAL  25.000MHZ IC  pkg 2013LF  page 101 : A = XTAL_CK_MNG_IN ; B = XTAL_CK_MNG_OUT

EU1A1  IR354XX  IR35411 IC  pkg SM  page 227
  VOS  = PVDDQ_KLM
  LGND  = GND
  VCC  = VR_PVDDQ_KLM_PH2_VCIN
  VDRV  = P5V_STBY
  PGND(0)  = GND
  GL(0)  = TP_PVDDQ_KLM_PH2_GL_0
  PGND(1)  = GND
  SW  = VR_PVDDQ_KLM_PH2_SW
  VIN(0)  = VR_FET_SW_P12V_STBY_PVDDQ_KLM
  VIN(1)  = VR_FET_SW_P12V_STBY_PVDDQ_KLM
  NC  = NC
  PHASE  = VR_PVDDQ_KLM_PH2_PHASE
  BOOST  = VR_PVDDQ_KLM_PH2_BOOT_R
  PWM  = VR_PVDDQ_KLM_PWM2
  EN  = P5V_STBY
  TOUT_FLT  = A_TSENSE_PVDDQ_KLM
  OCSET  = VR_PVDDQ_KLM_PH2_OCSET
  IOUT  = ISENSE_PVDDQ_KLM_PH2_IMON
  REFIN  = VR_PVDDQ_KLM_AIREF2
  PGND(2)  = GND
  GL(1)  = TP_PVDDQ_KLM_PH2_GL_1

(kicad_pcb
	(version 20260206)
	(generator "pcbnew")
	(generator_version "10.0")
	(general
		(thickness 1.6)
		(legacy_teardrops no)
	)
	(paper "A4")
	(title_block
		(title "Wiwynn_Tioga_Pass_MB.brd")
		(comment 1 "Tioga Pass / footprints 588-589 of 4770")
	)
	(layers
		(0 "F.Cu" signal "TOP")
		(4 "In1.Cu" signal "L2GND")
		(6 "In2.Cu" signal "L3")
		(8 "In3.Cu" signal "L4GND")
		(10 "In4.Cu" signal "L5")
		(12 "In5.Cu" signal "L6GND")
		(14 "In6.Cu" signal "L7VCC")
		(16 "In7.Cu" signal "L8VCC")
		(18 "In8.Cu" signal "L9GND")
		(20 "In9.Cu" signal "L10")
		(22 "In10.Cu" signal "L11GND")
		(24 "In11.Cu" signal "L12")
		(26 "In12.Cu" signal "L13GND")
		(2 "B.Cu" signal "BOTTOM")
		(9 "F.Adhes" user "F.Adhesive")
		(11 "B.Adhes" user "B.Adhesive")
		(13 "F.Paste" user "Package Geometry/Pastemask Top")
		(15 "B.Paste" user "Package Geometry/Pastemask Bottom")
		(5 "F.SilkS" user "Ref Des/Silkscreen Top")
		(7 "B.SilkS" user "Ref Des/Silkscreen Bottom")
		(1 "F.Mask" user "Board Geometry/Soldermask Top")
		(3 "B.Mask" user "Board Geometry/Soldermask Bottom")
		(17 "Dwgs.User" user "User.Drawings")
		(19 "Cmts.User" user "User.Comments")
		(21 "Eco1.User" user "User.Eco1")
		(23 "Eco2.User" user "User.Eco2")
		(25 "Edge.Cuts" user "Board Geometry/Outline")
		(27 "Margin" user)
		(31 "F.CrtYd" user "Package Geometry/Place Bound Top")
		(29 "B.CrtYd" user "Package Geometry/Place Bound Bottom")
		(35 "F.Fab" user "Ref Des/Assembly Top")
		(33 "B.Fab" user "Ref Des/Assembly Bottom")
	)
	(footprint ""
		(layer "F.Cu")
		(at 485.5845 -31.684468 180)
		(property "Reference" "Y8F1"
			(at -0.8001 3.55727 180)
			(unlocked yes)
			(layer "F.SilkS")
			(effects
				(font
					(size 0.7874 0.5842)
					(thickness 0.1524)
				)
				(justify left)
			)
		)
		(property "Value" ""
			(at 0 0 180)
			(layer "F.Fab")
			(effects
				(font
					(size 1.27 1.27)
				)
			)
		)
		(duplicate_pad_numbers_are_jumpers no)
		(fp_circle
			(center -1.049782 -0.44323)
			(end -1.176782 -0.44323)
			(stroke
				(width 0.254)
				(type default)
			)
			(fill no)
			(layer "F.SilkS")
		)
		(fp_rect
			(start -0.499872 2.70002)
			(end 2.100072 -0.599948)
			(stroke
				(width 0)
				(type default)
			)
			(fill no)
			(layer "F.CrtYd")
		)
		(fp_line
			(start 2.100072 2.70002)
			(end -0.499872 2.70002)
			(stroke
				(width 0.1)
				(type default)
			)
			(layer "F.Fab")
		)
		(fp_line
			(start 2.100072 -0.599948)
			(end 2.100072 2.70002)
			(stroke
				(width 0.1)
				(type default)
			)
			(layer "F.Fab")
		)
		(fp_line
			(start -0.499872 2.70002)
			(end -0.499872 -0.599948)
			(stroke
				(width 0.1)
				(type default)
			)
			(layer "F.Fab")
		)
		(fp_line
			(start -0.499872 -0.599948)
			(end 2.100072 -0.599948)
			(stroke
				(width 0.1)
				(type default)
			)
			(layer "F.Fab")
		)
		(fp_circle
			(center -1.049782 -0.44323)
			(end -1.176782 -0.44323)
			(stroke
				(width 0.254)
				(type default)
			)
			(fill no)
			(layer "F.Fab")
		)
		(pad "1" smd rect
			(at 0 0 180)
			(size 1.0414 1.143)
			(layers "F.Cu" "F.Mask" "F.Paste")
			(net "XTAL_CK_MNG_IN")
		)
		(pad "2" smd rect
			(at 0 2.100072 180)
			(size 1.0414 1.143)
			(layers "F.Cu" "F.Mask" "F.Paste")
			(net "GND")
		)
		(pad "3" smd rect
			(at 1.6002 2.100072 180)
			(size 1.0414 1.143)
			(layers "F.Cu" "F.Mask" "F.Paste")
			(net "XTAL_CK_MNG_OUT")
		)
		(pad "4" smd rect
			(at 1.6002 0 180)
			(size 1.0414 1.143)
			(layers "F.Cu" "F.Mask" "F.Paste")
			(net "GND")
		)
	)
	(footprint ""
		(layer "F.Cu")
		(at 2.397506 -147.328382 90)
		(property "Reference" "EU1A1"
			(at 3.292348 -1.686306 0)
			(unlocked yes)
			(layer "F.SilkS")
			(effects
				(font
					(size 0.7874 0.5842)
					(thickness 0.1524)
				)
			)
		)
		(property "Value" ""
			(at 0 0 90)
			(layer "F.Fab")
			(effects
				(font
					(size 1.27 1.27)
				)
			)
		)
		(duplicate_pad_numbers_are_jumpers no)
		(fp_line
			(start 2.9718 -3.5052)
			(end 2.9718 3.429)
			(stroke
				(width 0.1524)
				(type default)
			)
			(layer "F.SilkS")
		)
		(fp_line
			(start -3.0099 -3.5052)
			(end 2.9718 -3.5052)
			(stroke
				(width 0.1524)
				(type default)
			)
			(layer "F.SilkS")
		)
		(fp_line
			(start 2.9718 3.429)
			(end -3.0099 3.429)
			(stroke
				(width 0.1524)
				(type default)
			)
			(layer "F.SilkS")
		)
		(fp_line
			(start -3.0099 3.429)
			(end -3.0099 -3.5052)
			(stroke
				(width 0.1524)
				(type default)
			)
			(layer "F.SilkS")
		)
		(fp_circle
			(center -3.057398 -2.678684)
			(end -3.057398 -2.551684)
			(stroke
				(width 0.254)
				(type default)
			)
			(fill no)
			(layer "F.SilkS")
		)
		(fp_poly
			(pts
				(xy -2.9972 -3.4925) (xy -2.9972 -2.6924) (xy -2.1971 -3.4925)
			)
			(stroke
				(width 0)
				(type default)
			)
			(fill yes)
			(layer "F.SilkS")
		)
		(fp_poly
			(pts
				(xy -2.549906 -3.050032) (xy -2.549906 3.050032) (xy 2.549906 3.050032) (xy 2.549906 -3.050032)
			)
			(stroke
				(width 0)
				(type default)
			)
			(fill no)
			(layer "F.CrtYd")
		)
		(fp_line
			(start 2.549906 -3.050032)
			(end 2.549906 3.050032)
			(stroke
				(width 0.1)
				(type default)
			)
			(layer "F.Fab")
		)
		(fp_line
			(start -2.549906 -3.050032)
			(end 2.549906 -3.050032)
			(stroke
				(width 0.1)
				(type default)
			)
			(layer "F.Fab")
		)
		(fp_line
			(start 2.549906 3.050032)
			(end -2.549906 3.050032)
			(stroke
				(width 0.1)
				(type default)
			)
			(layer "F.Fab")
		)
		(fp_line
			(start -2.549906 3.050032)
			(end -2.549906 -3.050032)
			(stroke
				(width 0.1)
				(type default)
			)
			(layer "F.Fab")
		)
		(fp_circle
			(center -3.057398 -2.678684)
			(end -3.057398 -2.551684)
			(stroke
				(width 0.254)
				(type default)
			)
			(fill no)
			(layer "F.Fab")
		)
		(pad "1" smd rect
			(at -2.39522 -2.279904 90)
			(size 0.7112 0.254)
			(layers "F.Cu" "F.Mask" "F.Paste")
			(net "PVDDQ_KLM")
		)
		(pad "2" smd rect
			(at -2.39522 -1.83007 90)
			(size 0.7112 0.254)
			(layers "F.Cu" "F.Mask" "F.Paste")
			(net "GND")
		)
		(pad "3" smd rect
			(at -2.39522 -1.379982 90)
			(size 0.7112 0.254)
			(layers "F.Cu" "F.Mask" "F.Paste")
			(net "VR_PVDDQ_KLM_PH2_VCIN")
		)
		(pad "4" smd rect
			(at -2.39522 -0.929894 90)
			(size 0.7112 0.254)
			(layers "F.Cu" "F.Mask" "F.Paste")
			(net "P5V_STBY")
		)
		(pad "5" smd rect
			(at -2.39522 -0.48006 90)
			(size 0.7112 0.254)
			(layers "F.Cu" "F.Mask" "F.Paste")
			(net "GND")
		)
		(pad "6" smd rect
			(at -2.39522 -0.029972 90)
			(size 0.7112 0.254)
			(layers "F.Cu" "F.Mask" "F.Paste")
			(net "TP_PVDDQ_KLM_PH2_GL_0")
		)
		(pad "7" smd custom
			(at 0.016764 1.145032 90)
			(size 0.53975 0.53975)
			(layers "F.Cu" "F.Mask" "F.Paste")
			(net "GND")
			(options
				(clearance outline)
				(anchor circle)
			)
			(primitives
				(gr_poly
					(pts
						(xy -2.7051 1.0795) (xy -2.7051 -0.3683) (xy -0.9271 -0.3683) (xy -0.9271 -1.0795) (xy 2.7051 -1.0795)
						(xy 2.7051 1.0795)
					)
					(width 0)
					(fill yes)
				)
			)
		)
		(pad "10" smd rect
			(at -0.008382 2.874772 90)
			(size 4.3434 0.6096)
			(layers "F.Cu" "F.Mask" "F.Paste")
			(net "VR_PVDDQ_KLM_PH2_SW")
		)
		(pad "25" smd rect
			(at 1.548384 -1.283208 90)
			(size 2.3368 2.0066)
			(layers "F.Cu" "F.Mask" "F.Paste")
			(net "VR_FET_SW_P12V_STBY_PVDDQ_KLM")
		)
		(pad "30" smd rect
			(at 2.050034 -2.895092 90)
			(size 0.254 0.7112)
			(layers "F.Cu" "F.Mask" "F.Paste")
			(net "VR_FET_SW_P12V_STBY_PVDDQ_KLM")
		)
		(pad "31" smd rect
			(at 1.599946 -2.895092 90)
			(size 0.254 0.7112)
			(layers "F.Cu" "F.Mask" "F.Paste")
			(net "Net_373")
		)
		(pad "32" smd rect
			(at 1.150112 -2.895092 90)
			(size 0.254 0.7112)
			(layers "F.Cu" "F.Mask" "F.Paste")
			(net "VR_PVDDQ_KLM_PH2_PHASE")
		)
		(pad "33" smd rect
			(at 0.700024 -2.895092 90)
			(size 0.254 0.7112)
			(layers "F.Cu" "F.Mask" "F.Paste")
			(net "VR_PVDDQ_KLM_PH2_BOOT_R")
		)
		(pad "34" smd rect
			(at 0.249936 -2.895092 90)
			(size 0.254 0.7112)
			(layers "F.Cu" "F.Mask" "F.Paste")
			(net "VR_PVDDQ_KLM_PWM2")
		)
		(pad "35" smd rect
			(at -0.199898 -2.895092 90)
			(size 0.254 0.7112)
			(layers "F.Cu" "F.Mask" "F.Paste")
			(net "P5V_STBY")
		)
		(pad "36" smd rect
			(at -0.649986 -2.895092 90)
			(size 0.254 0.7112)
			(layers "F.Cu" "F.Mask" "F.Paste")
			(net "A_TSENSE_PVDDQ_KLM")
		)
		(pad "37" smd rect
			(at -1.100074 -2.895092 90)
			(size 0.254 0.7112)
			(layers "F.Cu" "F.Mask" "F.Paste")
			(net "VR_PVDDQ_KLM_PH2_OCSET")
		)
		(pad "38" smd rect
			(at -1.549908 -2.895092 90)
			(size 0.254 0.7112)
			(layers "F.Cu" "F.Mask" "F.Paste")
			(net "ISENSE_PVDDQ_KLM_PH2_IMON")
		)
		(pad "39" smd rect
			(at -1.999996 -2.895092 90)
			(size 0.254 0.7112)
			(layers "F.Cu" "F.Mask" "F.Paste")
			(net "VR_PVDDQ_KLM_AIREF2")
		)
		(pad "40" smd rect
			(at -0.871728 -1.283208 90)
			(size 1.8034 2.0066)
			(layers "F.Cu" "F.Mask" "F.Paste")
			(net "GND")
		)
		(pad "41" smd rect
			(at -1.533906 0.247904 90)
			(size 0.508 0.3556)
			(layers "F.Cu" "F.Mask" "F.Paste")
			(net "TP_PVDDQ_KLM_PH2_GL_1")
		)
	)
)
